# BASEBOARD_FAB2 (Tioga Pass) — schematic netlist excerpt (pin names and nets, part order shuffled) for the footprints in the layout excerpt that follows; sources: Cadence DE-HDL packaged netlist, KiCad conversion of Wiwynn_Tioga_Pass_MB.brd

R1U37  RES  100.0 1% CHIP  pkg 0402  page 152 : A = P0V7_GTL2014_2 ; B = GND
R1L15  RES  150.0 1% CHIP  pkg 0402  page 112 : A = PVCCIO_CPU0 ; B = XDP_CPU_TMS
C8D4  CAP_A  0.1UF 16V 10% X7R  pkg 0402V  page 196 : A = P3V3_STBY ; B = GND

(kicad_pcb
	(version 20260206)
	(generator "pcbnew")
	(generator_version "10.0")
	(general
		(thickness 1.6)
		(legacy_teardrops no)
	)
	(paper "A4")
	(title_block
		(title "Wiwynn_Tioga_Pass_MB.brd")
		(comment 1 "Tioga Pass / footprints 3025-3027 of 4770")
	)
	(layers
		(0 "F.Cu" signal "TOP")
		(4 "In1.Cu" signal "L2GND")
		(6 "In2.Cu" signal "L3")
		(8 "In3.Cu" signal "L4GND")
		(10 "In4.Cu" signal "L5")
		(12 "In5.Cu" signal "L6GND")
		(14 "In6.Cu" signal "L7VCC")
		(16 "In7.Cu" signal "L8VCC")
		(18 "In8.Cu" signal "L9GND")
		(20 "In9.Cu" signal "L10")
		(22 "In10.Cu" signal "L11GND")
		(24 "In11.Cu" signal "L12")
		(26 "In12.Cu" signal "L13GND")
		(2 "B.Cu" signal "BOTTOM")
		(9 "F.Adhes" user "F.Adhesive")
		(11 "B.Adhes" user "B.Adhesive")
		(13 "F.Paste" user "Package Geometry/Pastemask Top")
		(15 "B.Paste" user "Package Geometry/Pastemask Bottom")
		(5 "F.SilkS" user "Ref Des/Silkscreen Top")
		(7 "B.SilkS" user "Ref Des/Silkscreen Bottom")
		(1 "F.Mask" user "Board Geometry/Soldermask Top")
		(3 "B.Mask" user "Board Geometry/Soldermask Bottom")
		(17 "Dwgs.User" user "User.Drawings")
		(19 "Cmts.User" user "User.Comments")
		(21 "Eco1.User" user "User.Eco1")
		(23 "Eco2.User" user "User.Eco2")
		(25 "Edge.Cuts" user "Board Geometry/Outline")
		(27 "Margin" user)
		(31 "F.CrtYd" user "Package Geometry/Place Bound Top")
		(29 "B.CrtYd" user "Package Geometry/Place Bound Bottom")
		(35 "F.Fab" user "Ref Des/Assembly Top")
		(33 "B.Fab" user "Ref Des/Assembly Bottom")
	)
	(footprint ""
		(layer "B.Cu")
		(at 441.833 -13.1064 90)
		(property "Reference" "R1U37"
			(at 0 0 90)
			(layer "B.SilkS")
			(hide yes)
			(effects
				(font
					(size 1.27 1.27)
				)
				(justify mirror)
			)
		)
		(property "Value" ""
			(at 0 0 90)
			(layer "B.Fab")
			(effects
				(font
					(size 1.27 1.27)
				)
				(justify mirror)
			)
		)
		(duplicate_pad_numbers_are_jumpers no)
		(fp_poly
			(pts
				(xy 0.2794 -0.1016) (xy -0.2794 -0.1016) (xy -0.2794 0.9906) (xy 0.2794 0.9906)
			)
			(stroke
				(width 0)
				(type default)
			)
			(fill no)
			(layer "B.CrtYd")
		)
		(fp_line
			(start 0.2794 -0.1016)
			(end 0.2794 0.9906)
			(stroke
				(width 0.1)
				(type default)
			)
			(layer "B.Fab")
		)
		(fp_line
			(start -0.2794 -0.1016)
			(end 0.2794 -0.1016)
			(stroke
				(width 0.1)
				(type default)
			)
			(layer "B.Fab")
		)
		(fp_line
			(start 0.2794 0.9906)
			(end -0.2794 0.9906)
			(stroke
				(width 0.1)
				(type default)
			)
			(layer "B.Fab")
		)
		(fp_line
			(start -0.2794 0.9906)
			(end -0.2794 -0.1016)
			(stroke
				(width 0.1)
				(type default)
			)
			(layer "B.Fab")
		)
		(pad "1" smd rect
			(at 0 0 270)
			(size 0.508 0.508)
			(layers "B.Cu" "B.Mask" "B.Paste")
			(net "P0V7_GTL2014_2")
		)
		(pad "2" smd rect
			(at 0 0.889 270)
			(size 0.508 0.508)
			(layers "B.Cu" "B.Mask" "B.Paste")
			(net "GND")
		)
		(zone
			(layer "B.Cu")
			(hatch none 0.5)
			(connect_pads
				(clearance 0)
			)
			(min_thickness 0.25)
			(keepout
				(tracks allowed)
				(vias not_allowed)
				(pads allowed)
				(copperpour not_allowed)
				(footprints allowed)
			)
			(placement
				(enabled no)
				(sheetname "")
			)
			(fill
				(thermal_gap 0.5)
				(thermal_bridge_width 0.5)
				(island_removal_mode 0)
			)
			(polygon
				(pts
					(xy 442.087 -13.3604) (xy 442.087 -12.8524) (xy 442.468 -12.8524) (xy 442.468 -13.3604)
				)
			)
		)
		(zone
			(layer "B.Cu")
			(hatch none 0.5)
			(connect_pads
				(clearance 0)
			)
			(min_thickness 0.25)
			(keepout
				(tracks not_allowed)
				(vias allowed)
				(pads allowed)
				(copperpour not_allowed)
				(footprints allowed)
			)
			(placement
				(enabled no)
				(sheetname "")
			)
			(fill
				(thermal_gap 0.5)
				(thermal_bridge_width 0.5)
				(island_removal_mode 0)
			)
			(polygon
				(pts
					(xy 442.468 -13.3604) (xy 442.468 -12.8524) (xy 442.087 -12.8524) (xy 442.087 -13.3604)
				)
			)
		)
	)
	(footprint ""
		(layer "B.Cu")
		(at 411.4165 -4.318 -90)
		(property "Reference" "C8D4"
			(at 0 0 90)
			(layer "B.SilkS")
			(hide yes)
			(effects
				(font
					(size 1.27 1.27)
				)
				(justify mirror)
			)
		)
		(property "Value" ""
			(at 0 0 90)
			(layer "B.Fab")
			(effects
				(font
					(size 1.27 1.27)
				)
				(justify mirror)
			)
		)
		(duplicate_pad_numbers_are_jumpers no)
		(fp_poly
			(pts
				(xy -0.3048 -0.1016) (xy -0.3048 0.9906) (xy 0.3048 0.9906) (xy 0.3048 -0.1016)
			)
			(stroke
				(width 0)
				(type default)
			)
			(fill no)
			(layer "B.CrtYd")
		)
		(fp_line
			(start -0.3048 0.9906)
			(end -0.3048 -0.1016)
			(stroke
				(width 0.1)
				(type default)
			)
			(layer "B.Fab")
		)
		(fp_line
			(start 0.3048 0.9906)
			(end -0.3048 0.9906)
			(stroke
				(width 0.1)
				(type default)
			)
			(layer "B.Fab")
		)
		(fp_line
			(start -0.3048 -0.1016)
			(end 0.3048 -0.1016)
			(stroke
				(width 0.1)
				(type default)
			)
			(layer "B.Fab")
		)
		(fp_line
			(start 0.3048 -0.1016)
			(end 0.3048 0.9906)
			(stroke
				(width 0.1)
				(type default)
			)
			(layer "B.Fab")
		)
		(pad "1" smd rect
			(at 0 0 90)
			(size 0.508 0.508)
			(layers "B.Cu" "B.Mask" "B.Paste")
			(net "P3V3_STBY")
		)
		(pad "2" smd rect
			(at 0 0.889 90)
			(size 0.508 0.508)
			(layers "B.Cu" "B.Mask" "B.Paste")
			(net "GND")
		)
		(zone
			(layer "B.Cu")
			(hatch none 0.5)
			(connect_pads
				(clearance 0)
			)
			(min_thickness 0.25)
			(keepout
				(tracks not_allowed)
				(vias allowed)
				(pads allowed)
				(copperpour not_allowed)
				(footprints allowed)
			)
			(placement
				(enabled no)
				(sheetname "")
			)
			(fill
				(thermal_gap 0.5)
				(thermal_bridge_width 0.5)
				(island_removal_mode 0)
			)
			(polygon
				(pts
					(xy 410.7815 -4.064) (xy 410.7815 -4.572) (xy 411.1625 -4.572) (xy 411.1625 -4.064)
				)
			)
		)
		(zone
			(layer "B.Cu")
			(hatch none 0.5)
			(connect_pads
				(clearance 0)
			)
			(min_thickness 0.25)
			(keepout
				(tracks allowed)
				(vias not_allowed)
				(pads allowed)
				(copperpour not_allowed)
				(footprints allowed)
			)
			(placement
				(enabled no)
				(sheetname "")
			)
			(fill
				(thermal_gap 0.5)
				(thermal_bridge_width 0.5)
				(island_removal_mode 0)
			)
			(polygon
				(pts
					(xy 411.1625 -4.064) (xy 411.1625 -4.572) (xy 410.7815 -4.572) (xy 410.7815 -4.064)
				)
			)
		)
	)
	(footprint ""
		(layer "B.Cu")
		(at 461.277208 -147.650454 90)
		(property "Reference" "R1L15"
			(at 0 0 90)
			(layer "B.SilkS")
			(hide yes)
			(effects
				(font
					(size 1.27 1.27)
				)
				(justify mirror)
			)
		)
		(property "Value" ""
			(at 0 0 90)
			(layer "B.Fab")
			(effects
				(font
					(size 1.27 1.27)
				)
				(justify mirror)
			)
		)
		(duplicate_pad_numbers_are_jumpers no)
		(fp_poly
			(pts
				(xy 0.2794 -0.1016) (xy -0.2794 -0.1016) (xy -0.2794 0.9906) (xy 0.2794 0.9906)
			)
			(stroke
				(width 0)
				(type default)
			)
			(fill no)
			(layer "B.CrtYd")
		)
		(fp_line
			(start 0.2794 -0.1016)
			(end 0.2794 0.9906)
			(stroke
				(width 0.1)
				(type default)
			)
			(layer "B.Fab")
		)
		(fp_line
			(start -0.2794 -0.1016)
			(end 0.2794 -0.1016)
			(stroke
				(width 0.1)
				(type default)
			)
			(layer "B.Fab")
		)
		(fp_line
			(start 0.2794 0.9906)
			(end -0.2794 0.9906)
			(stroke
				(width 0.1)
				(type default)
			)
			(layer "B.Fab")
		)
		(fp_line
			(start -0.2794 0.9906)
			(end -0.2794 -0.1016)
			(stroke
				(width 0.1)
				(type default)
			)
			(layer "B.Fab")
		)
		(pad "1" smd rect
			(at 0 0 270)
			(size 0.508 0.508)
			(layers "B.Cu" "B.Mask" "B.Paste")
			(net "PVCCIO_CPU0")
		)
		(pad "2" smd rect
			(at 0 0.889 270)
			(size 0.508 0.508)
			(layers "B.Cu" "B.Mask" "B.Paste")
			(net "XDP_CPU_TMS")
		)
		(zone
			(layer "B.Cu")
			(hatch none 0.5)
			(connect_pads
				(clearance 0)
			)
			(min_thickness 0.25)
			(keepout
				(tracks allowed)
				(vias not_allowed)
				(pads allowed)
				(copperpour not_allowed)
				(footprints allowed)
			)
			(placement
				(enabled no)
				(sheetname "")
			)
			(fill
				(thermal_gap 0.5)
				(thermal_bridge_width 0.5)
				(island_removal_mode 0)
			)
			(polygon
				(pts
					(xy 461.531208 -147.904454) (xy 461.531208 -147.396454) (xy 461.912208 -147.396454) (xy 461.912208 -147.904454)
				)
			)
		)
		(zone
			(layer "B.Cu")
			(hatch none 0.5)
			(connect_pads
				(clearance 0)
			)
			(min_thickness 0.25)
			(keepout
				(tracks not_allowed)
				(vias allowed)
				(pads allowed)
				(copperpour not_allowed)
				(footprints allowed)
			)
			(placement
				(enabled no)
				(sheetname "")
			)
			(fill
				(thermal_gap 0.5)
				(thermal_bridge_width 0.5)
				(island_removal_mode 0)
			)
			(polygon
				(pts
					(xy 461.912208 -147.904454) (xy 461.912208 -147.396454) (xy 461.531208 -147.396454) (xy 461.531208 -147.904454)
				)
			)
		)
	)
)
